# BASEBOARD_FAB2 (Tioga Pass) — schematic netlist excerpt (pin names and nets, part order shuffled) for the footprints in the layout excerpt that follows; sources: Cadence DE-HDL packaged netlist, KiCad conversion of Wiwynn_Tioga_Pass_MB.brd

R2M4  RES  1.00K 1% CHIP  pkg 0402  page 133 : A = P3V3_STBY ; B = IRQ_HSC_FAULT_N
C4D38  CAP_A  0.1UF 16V 10% X7R  pkg 0402V  page 213 : A = VR_PVCCIO_CPU1_VDD ; B = GND
R8B19  RES  4.75K 1% CHIP  pkg 0402  page 91 : A = PVPP_ABC ; B = FM_MODPRST_HFI1_CPU0_LVT2_N

(kicad_pcb
	(version 20260206)
	(generator "pcbnew")
	(generator_version "10.0")
	(general
		(thickness 1.6)
		(legacy_teardrops no)
	)
	(paper "A4")
	(title_block
		(title "Wiwynn_Tioga_Pass_MB.brd")
		(comment 1 "Tioga Pass / footprints 1849-1851 of 4770")
	)
	(layers
		(0 "F.Cu" signal "TOP")
		(4 "In1.Cu" signal "L2GND")
		(6 "In2.Cu" signal "L3")
		(8 "In3.Cu" signal "L4GND")
		(10 "In4.Cu" signal "L5")
		(12 "In5.Cu" signal "L6GND")
		(14 "In6.Cu" signal "L7VCC")
		(16 "In7.Cu" signal "L8VCC")
		(18 "In8.Cu" signal "L9GND")
		(20 "In9.Cu" signal "L10")
		(22 "In10.Cu" signal "L11GND")
		(24 "In11.Cu" signal "L12")
		(26 "In12.Cu" signal "L13GND")
		(2 "B.Cu" signal "BOTTOM")
		(9 "F.Adhes" user "F.Adhesive")
		(11 "B.Adhes" user "B.Adhesive")
		(13 "F.Paste" user "Package Geometry/Pastemask Top")
		(15 "B.Paste" user "Package Geometry/Pastemask Bottom")
		(5 "F.SilkS" user "Ref Des/Silkscreen Top")
		(7 "B.SilkS" user "Ref Des/Silkscreen Bottom")
		(1 "F.Mask" user "Board Geometry/Soldermask Top")
		(3 "B.Mask" user "Board Geometry/Soldermask Bottom")
		(17 "Dwgs.User" user "User.Drawings")
		(19 "Cmts.User" user "User.Comments")
		(21 "Eco1.User" user "User.Eco1")
		(23 "Eco2.User" user "User.Eco2")
		(25 "Edge.Cuts" user "Board Geometry/Outline")
		(27 "Margin" user)
		(31 "F.CrtYd" user "Package Geometry/Place Bound Top")
		(29 "B.CrtYd" user "Package Geometry/Place Bound Bottom")
		(35 "F.Fab" user "Ref Des/Assembly Top")
		(33 "B.Fab" user "Ref Des/Assembly Bottom")
	)
	(footprint ""
		(layer "F.Cu")
		(at 414.5788 -112.2426 90)
		(property "Reference" "R2M4"
			(at 0 0 90)
			(layer "F.SilkS")
			(hide yes)
			(effects
				(font
					(size 1.27 1.27)
				)
			)
		)
		(property "Value" ""
			(at 0 0 90)
			(layer "F.Fab")
			(effects
				(font
					(size 1.27 1.27)
				)
			)
		)
		(duplicate_pad_numbers_are_jumpers no)
		(fp_poly
			(pts
				(xy -0.2794 -0.1016) (xy 0.2794 -0.1016) (xy 0.2794 0.9906) (xy -0.2794 0.9906)
			)
			(stroke
				(width 0)
				(type default)
			)
			(fill no)
			(layer "F.CrtYd")
		)
		(fp_line
			(start 0.2794 -0.1016)
			(end -0.2794 -0.1016)
			(stroke
				(width 0.1)
				(type default)
			)
			(layer "F.Fab")
		)
		(fp_line
			(start -0.2794 -0.1016)
			(end -0.2794 0.9906)
			(stroke
				(width 0.1)
				(type default)
			)
			(layer "F.Fab")
		)
		(fp_line
			(start 0.2794 0.9906)
			(end 0.2794 -0.1016)
			(stroke
				(width 0.1)
				(type default)
			)
			(layer "F.Fab")
		)
		(fp_line
			(start -0.2794 0.9906)
			(end 0.2794 0.9906)
			(stroke
				(width 0.1)
				(type default)
			)
			(layer "F.Fab")
		)
		(pad "1" smd rect
			(at 0 0 90)
			(size 0.508 0.508)
			(layers "F.Cu" "F.Mask" "F.Paste")
			(net "P3V3_STBY")
		)
		(pad "2" smd rect
			(at 0 0.889 90)
			(size 0.508 0.508)
			(layers "F.Cu" "F.Mask" "F.Paste")
			(net "IRQ_HSC_FAULT_N")
		)
		(zone
			(layer "F.Cu")
			(hatch none 0.5)
			(connect_pads
				(clearance 0)
			)
			(min_thickness 0.25)
			(keepout
				(tracks allowed)
				(vias not_allowed)
				(pads allowed)
				(copperpour not_allowed)
				(footprints allowed)
			)
			(placement
				(enabled no)
				(sheetname "")
			)
			(fill
				(thermal_gap 0.5)
				(thermal_bridge_width 0.5)
				(island_removal_mode 0)
			)
			(polygon
				(pts
					(xy 414.8328 -111.9886) (xy 414.8328 -112.4966) (xy 415.2138 -112.4966) (xy 415.2138 -111.9886)
				)
			)
		)
		(zone
			(layer "F.Cu")
			(hatch none 0.5)
			(connect_pads
				(clearance 0)
			)
			(min_thickness 0.25)
			(keepout
				(tracks not_allowed)
				(vias allowed)
				(pads allowed)
				(copperpour not_allowed)
				(footprints allowed)
			)
			(placement
				(enabled no)
				(sheetname "")
			)
			(fill
				(thermal_gap 0.5)
				(thermal_bridge_width 0.5)
				(island_removal_mode 0)
			)
			(polygon
				(pts
					(xy 415.2138 -111.9886) (xy 415.2138 -112.4966) (xy 414.8328 -112.4966) (xy 414.8328 -111.9886)
				)
			)
		)
	)
	(footprint ""
		(layer "F.Cu")
		(at 173.9265 -68.834 90)
		(property "Reference" "C4D38"
			(at 0 0 90)
			(layer "F.SilkS")
			(hide yes)
			(effects
				(font
					(size 1.27 1.27)
				)
			)
		)
		(property "Value" ""
			(at 0 0 90)
			(layer "F.Fab")
			(effects
				(font
					(size 1.27 1.27)
				)
			)
		)
		(duplicate_pad_numbers_are_jumpers no)
		(fp_poly
			(pts
				(xy 0.3048 -0.1016) (xy 0.3048 0.9906) (xy -0.3048 0.9906) (xy -0.3048 -0.1016)
			)
			(stroke
				(width 0)
				(type default)
			)
			(fill no)
			(layer "F.CrtYd")
		)
		(fp_line
			(start 0.3048 -0.1016)
			(end -0.3048 -0.1016)
			(stroke
				(width 0.1)
				(type default)
			)
			(layer "F.Fab")
		)
		(fp_line
			(start -0.3048 -0.1016)
			(end -0.3048 0.9906)
			(stroke
				(width 0.1)
				(type default)
			)
			(layer "F.Fab")
		)
		(fp_line
			(start 0.3048 0.9906)
			(end 0.3048 -0.1016)
			(stroke
				(width 0.1)
				(type default)
			)
			(layer "F.Fab")
		)
		(fp_line
			(start -0.3048 0.9906)
			(end 0.3048 0.9906)
			(stroke
				(width 0.1)
				(type default)
			)
			(layer "F.Fab")
		)
		(pad "1" smd rect
			(at 0 0 90)
			(size 0.508 0.508)
			(layers "F.Cu" "F.Mask" "F.Paste")
			(net "VR_PVCCIO_CPU1_VDD")
		)
		(pad "2" smd rect
			(at 0 0.889 90)
			(size 0.508 0.508)
			(layers "F.Cu" "F.Mask" "F.Paste")
			(net "GND")
		)
		(zone
			(layer "F.Cu")
			(hatch none 0.5)
			(connect_pads
				(clearance 0)
			)
			(min_thickness 0.25)
			(keepout
				(tracks allowed)
				(vias not_allowed)
				(pads allowed)
				(copperpour not_allowed)
				(footprints allowed)
			)
			(placement
				(enabled no)
				(sheetname "")
			)
			(fill
				(thermal_gap 0.5)
				(thermal_bridge_width 0.5)
				(island_removal_mode 0)
			)
			(polygon
				(pts
					(xy 174.1805 -68.58) (xy 174.1805 -69.088) (xy 174.5615 -69.088) (xy 174.5615 -68.58)
				)
			)
		)
		(zone
			(layer "F.Cu")
			(hatch none 0.5)
			(connect_pads
				(clearance 0)
			)
			(min_thickness 0.25)
			(keepout
				(tracks not_allowed)
				(vias allowed)
				(pads allowed)
				(copperpour not_allowed)
				(footprints allowed)
			)
			(placement
				(enabled no)
				(sheetname "")
			)
			(fill
				(thermal_gap 0.5)
				(thermal_bridge_width 0.5)
				(island_removal_mode 0)
			)
			(polygon
				(pts
					(xy 174.5615 -68.58) (xy 174.5615 -69.088) (xy 174.1805 -69.088) (xy 174.1805 -68.58)
				)
			)
		)
	)
	(footprint ""
		(layer "F.Cu")
		(at 421.894 -117.4877 180)
		(property "Reference" "R8B19"
			(at 0 0 180)
			(layer "F.SilkS")
			(hide yes)
			(effects
				(font
					(size 1.27 1.27)
				)
			)
		)
		(property "Value" ""
			(at 0 0 180)
			(layer "F.Fab")
			(effects
				(font
					(size 1.27 1.27)
				)
			)
		)
		(duplicate_pad_numbers_are_jumpers no)
		(fp_poly
			(pts
				(xy -0.2794 -0.1016) (xy 0.2794 -0.1016) (xy 0.2794 0.9906) (xy -0.2794 0.9906)
			)
			(stroke
				(width 0)
				(type default)
			)
			(fill no)
			(layer "F.CrtYd")
		)
		(fp_line
			(start 0.2794 0.9906)
			(end 0.2794 -0.1016)
			(stroke
				(width 0.1)
				(type default)
			)
			(layer "F.Fab")
		)
		(fp_line
			(start 0.2794 -0.1016)
			(end -0.2794 -0.1016)
			(stroke
				(width 0.1)
				(type default)
			)
			(layer "F.Fab")
		)
		(fp_line
			(start -0.2794 0.9906)
			(end 0.2794 0.9906)
			(stroke
				(width 0.1)
				(type default)
			)
			(layer "F.Fab")
		)
		(fp_line
			(start -0.2794 -0.1016)
			(end -0.2794 0.9906)
			(stroke
				(width 0.1)
				(type default)
			)
			(layer "F.Fab")
		)
		(pad "1" smd rect
			(at 0 0 180)
			(size 0.508 0.508)
			(layers "F.Cu" "F.Mask" "F.Paste")
			(net "PVPP_ABC")
		)
		(pad "2" smd rect
			(at 0 0.889 180)
			(size 0.508 0.508)
			(layers "F.Cu" "F.Mask" "F.Paste")
			(net "FM_MODPRST_HFI1_CPU0_LVT2_N")
		)
		(zone
			(layer "F.Cu")
			(hatch none 0.5)
			(connect_pads
				(clearance 0)
			)
			(min_thickness 0.25)
			(keepout
				(tracks not_allowed)
				(vias allowed)
				(pads allowed)
				(copperpour not_allowed)
				(footprints allowed)
			)
			(placement
				(enabled no)
				(sheetname "")
			)
			(fill
				(thermal_gap 0.5)
				(thermal_bridge_width 0.5)
				(island_removal_mode 0)
			)
			(polygon
				(pts
					(xy 422.148 -118.1227) (xy 421.64 -118.1227) (xy 421.64 -117.7417) (xy 422.148 -117.7417)
				)
			)
		)
		(zone
			(layer "F.Cu")
			(hatch none 0.5)
			(connect_pads
				(clearance 0)
			)
			(min_thickness 0.25)
			(keepout
				(tracks allowed)
				(vias not_allowed)
				(pads allowed)
				(copperpour not_allowed)
				(footprints allowed)
			)
			(placement
				(enabled no)
				(sheetname "")
			)
			(fill
				(thermal_gap 0.5)
				(thermal_bridge_width 0.5)
				(island_removal_mode 0)
			)
			(polygon
				(pts
					(xy 422.148 -117.7417) (xy 421.64 -117.7417) (xy 421.64 -118.1227) (xy 422.148 -118.1227)
				)
			)
		)
	)
)
